(kicad_pcb
	(version 20260206)
	(generator "pcbnew")
	(generator_version "10.0")
	(general
		(thickness 1.6)
		(legacy_teardrops no)
	)
	(paper "A4")
	(title_block
		(title "Wiwynn_Tioga_Pass_MB.brd")
		(comment 1 "Tioga Pass / footprints 4121-4128 of 4770")
	)
	(layers
		(0 "F.Cu" signal "TOP")
		(4 "In1.Cu" signal "L2GND")
		(6 "In2.Cu" signal "L3")
		(8 "In3.Cu" signal "L4GND")
		(10 "In4.Cu" signal "L5")
		(12 "In5.Cu" signal "L6GND")
		(14 "In6.Cu" signal "L7VCC")
		(16 "In7.Cu" signal "L8VCC")
		(18 "In8.Cu" signal "L9GND")
		(20 "In9.Cu" signal "L10")
		(22 "In10.Cu" signal "L11GND")
		(24 "In11.Cu" signal "L12")
		(26 "In12.Cu" signal "L13GND")
		(2 "B.Cu" signal "BOTTOM")
		(9 "F.Adhes" user "F.Adhesive")
		(11 "B.Adhes" user "B.Adhesive")
		(13 "F.Paste" user "Package Geometry/Pastemask Top")
		(15 "B.Paste" user "Package Geometry/Pastemask Bottom")
		(5 "F.SilkS" user "Ref Des/Silkscreen Top")
		(7 "B.SilkS" user "Ref Des/Silkscreen Bottom")
		(1 "F.Mask" user "Board Geometry/Soldermask Top")
		(3 "B.Mask" user "Board Geometry/Soldermask Bottom")
		(17 "Dwgs.User" user "User.Drawings")
		(19 "Cmts.User" user "User.Comments")
		(21 "Eco1.User" user "User.Eco1")
		(23 "Eco2.User" user "User.Eco2")
		(25 "Edge.Cuts" user "Board Geometry/Outline")
		(27 "Margin" user)
		(31 "F.CrtYd" user "Package Geometry/Place Bound Top")
		(29 "B.CrtYd" user "Package Geometry/Place Bound Bottom")
		(35 "F.Fab" user "Ref Des/Assembly Top")
		(33 "B.Fab" user "Ref Des/Assembly Bottom")
	)
	(footprint ""
		(layer "B.Cu")
		(at 276.000464 -145.0086 90)
		(property "Reference" "C5L6"
			(at -1.848866 0.752348 90)
			(unlocked yes)
			(layer "B.SilkS")
			(effects
				(font
					(size 1.27 0.9652)
					(thickness 0.1524)
				)
				(justify mirror)
			)
		)
		(property "Value" ""
			(at 0 0 90)
			(layer "B.Fab")
			(effects
				(font
					(size 1.27 1.27)
				)
				(justify mirror)
			)
		)
		(duplicate_pad_numbers_are_jumpers no)
		(fp_rect
			(start 0.500126 1.598422)
			(end -0.500126 -0.201422)
			(stroke
				(width 0)
				(type default)
			)
			(fill no)
			(layer "B.CrtYd")
		)
		(fp_line
			(start 0.500126 -0.201422)
			(end -0.500126 -0.201422)
			(stroke
				(width 0.1)
				(type default)
			)
			(layer "B.Fab")
		)
		(fp_line
			(start -0.500126 -0.201422)
			(end -0.500126 1.598422)
			(stroke
				(width 0.1)
				(type default)
			)
			(layer "B.Fab")
		)
		(fp_line
			(start 0.500126 1.598422)
			(end 0.500126 -0.201422)
			(stroke
				(width 0.1)
				(type default)
			)
			(layer "B.Fab")
		)
		(fp_line
			(start -0.500126 1.598422)
			(end 0.500126 1.598422)
			(stroke
				(width 0.1)
				(type default)
			)
			(layer "B.Fab")
		)
		(pad "1" smd rect
			(at 0 0)
			(size 0.889 0.9906)
			(layers "B.Cu" "B.Mask" "B.Paste")
			(net "PVDDQ_DEF")
		)
		(pad "2" smd rect
			(at 0 1.397)
			(size 0.889 0.9906)
			(layers "B.Cu" "B.Mask" "B.Paste")
			(net "GND")
		)
		(zone
			(layer "B.Cu")
			(hatch none 0.5)
			(connect_pads
				(clearance 0)
			)
			(min_thickness 0.25)
			(keepout
				(tracks not_allowed)
				(vias allowed)
				(pads allowed)
				(copperpour not_allowed)
				(footprints allowed)
			)
			(placement
				(enabled no)
				(sheetname "")
			)
			(fill
				(thermal_gap 0.5)
				(thermal_bridge_width 0.5)
				(island_removal_mode 0)
			)
			(polygon
				(pts
					(xy 276.952964 -145.5039) (xy 276.444964 -145.5039) (xy 276.444964 -144.5133) (xy 276.952964 -144.5133)
				)
			)
		)
		(zone
			(layer "B.Cu")
			(hatch none 0.5)
			(connect_pads
				(clearance 0)
			)
			(min_thickness 0.25)
			(keepout
				(tracks allowed)
				(vias not_allowed)
				(pads allowed)
				(copperpour not_allowed)
				(footprints allowed)
			)
			(placement
				(enabled no)
				(sheetname "")
			)
			(fill
				(thermal_gap 0.5)
				(thermal_bridge_width 0.5)
				(island_removal_mode 0)
			)
			(polygon
				(pts
					(xy 276.952964 -145.5039) (xy 276.444964 -145.5039) (xy 276.444964 -144.5133) (xy 276.952964 -144.5133)
				)
			)
		)
	)
	(footprint ""
		(layer "B.Cu")
		(at 266.245086 -79.60614 180)
		(property "Reference" "C5P15"
			(at 0 0 0)
			(layer "B.SilkS")
			(hide yes)
			(effects
				(font
					(size 1.27 1.27)
				)
				(justify mirror)
			)
		)
		(property "Value" ""
			(at 0 0 0)
			(layer "B.Fab")
			(effects
				(font
					(size 1.27 1.27)
				)
				(justify mirror)
			)
		)
		(duplicate_pad_numbers_are_jumpers no)
		(fp_poly
			(pts
				(xy 0.7239 -0.2159) (xy -0.7239 -0.2159) (xy -0.7239 1.9939) (xy 0.7239 1.9939)
			)
			(stroke
				(width 0)
				(type default)
			)
			(fill no)
			(layer "B.CrtYd")
		)
		(fp_line
			(start 0.7239 1.9939)
			(end -0.7239 1.9939)
			(stroke
				(width 0.1)
				(type default)
			)
			(layer "B.Fab")
		)
		(fp_line
			(start 0.7239 -0.2159)
			(end 0.7239 1.9939)
			(stroke
				(width 0.1)
				(type default)
			)
			(layer "B.Fab")
		)
		(fp_line
			(start -0.7239 1.9939)
			(end -0.7239 -0.2159)
			(stroke
				(width 0.1)
				(type default)
			)
			(layer "B.Fab")
		)
		(fp_line
			(start -0.7239 -0.2159)
			(end 0.7239 -0.2159)
			(stroke
				(width 0.1)
				(type default)
			)
			(layer "B.Fab")
		)
		(pad "1" smd rect
			(at 0 0)
			(size 1.27 1.016)
			(layers "B.Cu" "B.Mask" "B.Paste")
			(net "PVCCIN_CPU0")
		)
		(pad "2" smd rect
			(at 0 1.778)
			(size 1.27 1.016)
			(layers "B.Cu" "B.Mask" "B.Paste")
			(net "GND")
		)
		(zone
			(layer "B.Cu")
			(hatch none 0.5)
			(connect_pads
				(clearance 0)
			)
			(min_thickness 0.25)
			(keepout
				(tracks not_allowed)
				(vias allowed)
				(pads allowed)
				(copperpour not_allowed)
				(footprints allowed)
			)
			(placement
				(enabled no)
				(sheetname "")
			)
			(fill
				(thermal_gap 0.5)
				(thermal_bridge_width 0.5)
				(island_removal_mode 0)
			)
			(polygon
				(pts
					(xy 265.610086 -80.11414) (xy 266.880086 -80.11414) (xy 266.880086 -80.87614) (xy 265.610086 -80.87614)
				)
			)
		)
	)
	(footprint ""
		(layer "B.Cu")
		(at 372.872 -6.1595)
		(property "Reference" "R7G27"
			(at 0 0 0)
			(layer "B.SilkS")
			(hide yes)
			(effects
				(font
					(size 1.27 1.27)
				)
				(justify mirror)
			)
		)
		(property "Value" ""
			(at 0 0 0)
			(layer "B.Fab")
			(effects
				(font
					(size 1.27 1.27)
				)
				(justify mirror)
			)
		)
		(duplicate_pad_numbers_are_jumpers no)
		(fp_poly
			(pts
				(xy 0.2794 -0.1016) (xy -0.2794 -0.1016) (xy -0.2794 0.9906) (xy 0.2794 0.9906)
			)
			(stroke
				(width 0)
				(type default)
			)
			(fill no)
			(layer "B.CrtYd")
		)
		(fp_line
			(start -0.2794 -0.1016)
			(end 0.2794 -0.1016)
			(stroke
				(width 0.1)
				(type default)
			)
			(layer "B.Fab")
		)
		(fp_line
			(start -0.2794 0.9906)
			(end -0.2794 -0.1016)
			(stroke
				(width 0.1)
				(type default)
			)
			(layer "B.Fab")
		)
		(fp_line
			(start 0.2794 -0.1016)
			(end 0.2794 0.9906)
			(stroke
				(width 0.1)
				(type default)
			)
			(layer "B.Fab")
		)
		(fp_line
			(start 0.2794 0.9906)
			(end -0.2794 0.9906)
			(stroke
				(width 0.1)
				(type default)
			)
			(layer "B.Fab")
		)
		(pad "1" smd rect
			(at 0 0 180)
			(size 0.508 0.508)
			(layers "B.Cu" "B.Mask" "B.Paste")
			(net "P3V3_STBY")
		)
		(pad "2" smd rect
			(at 0 0.889 180)
			(size 0.508 0.508)
			(layers "B.Cu" "B.Mask" "B.Paste")
			(net "PU_BIOS_USB_RECOVERY")
		)
		(zone
			(layer "B.Cu")
			(hatch none 0.5)
			(connect_pads
				(clearance 0)
			)
			(min_thickness 0.25)
			(keepout
				(tracks allowed)
				(vias not_allowed)
				(pads allowed)
				(copperpour not_allowed)
				(footprints allowed)
			)
			(placement
				(enabled no)
				(sheetname "")
			)
			(fill
				(thermal_gap 0.5)
				(thermal_bridge_width 0.5)
				(island_removal_mode 0)
			)
			(polygon
				(pts
					(xy 373.126 -5.9055) (xy 372.618 -5.9055) (xy 372.618 -5.5245) (xy 373.126 -5.5245)
				)
			)
		)
		(zone
			(layer "B.Cu")
			(hatch none 0.5)
			(connect_pads
				(clearance 0)
			)
			(min_thickness 0.25)
			(keepout
				(tracks not_allowed)
				(vias allowed)
				(pads allowed)
				(copperpour not_allowed)
				(footprints allowed)
			)
			(placement
				(enabled no)
				(sheetname "")
			)
			(fill
				(thermal_gap 0.5)
				(thermal_bridge_width 0.5)
				(island_removal_mode 0)
			)
			(polygon
				(pts
					(xy 373.126 -5.5245) (xy 372.618 -5.5245) (xy 372.618 -5.9055) (xy 373.126 -5.9055)
				)
			)
		)
	)
	(footprint ""
		(layer "B.Cu")
		(at 421.513 -81.4705)
		(property "Reference" "R2P13"
			(at 0 0 0)
			(layer "B.SilkS")
			(hide yes)
			(effects
				(font
					(size 1.27 1.27)
				)
				(justify mirror)
			)
		)
		(property "Value" ""
			(at 0 0 0)
			(layer "B.Fab")
			(effects
				(font
					(size 1.27 1.27)
				)
				(justify mirror)
			)
		)
		(duplicate_pad_numbers_are_jumpers no)
		(fp_poly
			(pts
				(xy 0.2794 -0.1016) (xy -0.2794 -0.1016) (xy -0.2794 0.9906) (xy 0.2794 0.9906)
			)
			(stroke
				(width 0)
				(type default)
			)
			(fill no)
			(layer "B.CrtYd")
		)
		(fp_line
			(start -0.2794 -0.1016)
			(end 0.2794 -0.1016)
			(stroke
				(width 0.1)
				(type default)
			)
			(layer "B.Fab")
		)
		(fp_line
			(start -0.2794 0.9906)
			(end -0.2794 -0.1016)
			(stroke
				(width 0.1)
				(type default)
			)
			(layer "B.Fab")
		)
		(fp_line
			(start 0.2794 -0.1016)
			(end 0.2794 0.9906)
			(stroke
				(width 0.1)
				(type default)
			)
			(layer "B.Fab")
		)
		(fp_line
			(start 0.2794 0.9906)
			(end -0.2794 0.9906)
			(stroke
				(width 0.1)
				(type default)
			)
			(layer "B.Fab")
		)
		(pad "1" smd rect
			(at 0 0 180)
			(size 0.508 0.508)
			(layers "B.Cu" "B.Mask" "B.Paste")
			(net "P3V3_STBY")
		)
		(pad "2" smd rect
			(at 0 0.889 180)
			(size 0.508 0.508)
			(layers "B.Cu" "B.Mask" "B.Paste")
			(net "FM_PMBUS_ALERT_BUF_EN_N")
		)
		(zone
			(layer "B.Cu")
			(hatch none 0.5)
			(connect_pads
				(clearance 0)
			)
			(min_thickness 0.25)
			(keepout
				(tracks allowed)
				(vias not_allowed)
				(pads allowed)
				(copperpour not_allowed)
				(footprints allowed)
			)
			(placement
				(enabled no)
				(sheetname "")
			)
			(fill
				(thermal_gap 0.5)
				(thermal_bridge_width 0.5)
				(island_removal_mode 0)
			)
			(polygon
				(pts
					(xy 421.767 -81.2165) (xy 421.259 -81.2165) (xy 421.259 -80.8355) (xy 421.767 -80.8355)
				)
			)
		)
		(zone
			(layer "B.Cu")
			(hatch none 0.5)
			(connect_pads
				(clearance 0)
			)
			(min_thickness 0.25)
			(keepout
				(tracks not_allowed)
				(vias allowed)
				(pads allowed)
				(copperpour not_allowed)
				(footprints allowed)
			)
			(placement
				(enabled no)
				(sheetname "")
			)
			(fill
				(thermal_gap 0.5)
				(thermal_bridge_width 0.5)
				(island_removal_mode 0)
			)
			(polygon
				(pts
					(xy 421.767 -80.8355) (xy 421.259 -80.8355) (xy 421.259 -81.2165) (xy 421.767 -81.2165)
				)
			)
		)
	)
	(footprint ""
		(layer "B.Cu")
		(at 64.262 -64.7954 180)
		(property "Reference" "R1E8"
			(at 0 0 0)
			(layer "B.SilkS")
			(hide yes)
			(effects
				(font
					(size 1.27 1.27)
				)
				(justify mirror)
			)
		)
		(property "Value" ""
			(at 0 0 0)
			(layer "B.Fab")
			(effects
				(font
					(size 1.27 1.27)
				)
				(justify mirror)
			)
		)
		(duplicate_pad_numbers_are_jumpers no)
		(fp_poly
			(pts
				(xy 0.2794 -0.1016) (xy -0.2794 -0.1016) (xy -0.2794 0.9906) (xy 0.2794 0.9906)
			)
			(stroke
				(width 0)
				(type default)
			)
			(fill no)
			(layer "B.CrtYd")
		)
		(fp_line
			(start 0.2794 0.9906)
			(end -0.2794 0.9906)
			(stroke
				(width 0.1)
				(type default)
			)
			(layer "B.Fab")
		)
		(fp_line
			(start 0.2794 -0.1016)
			(end 0.2794 0.9906)
			(stroke
				(width 0.1)
				(type default)
			)
			(layer "B.Fab")
		)
		(fp_line
			(start -0.2794 0.9906)
			(end -0.2794 -0.1016)
			(stroke
				(width 0.1)
				(type default)
			)
			(layer "B.Fab")
		)
		(fp_line
			(start -0.2794 -0.1016)
			(end 0.2794 -0.1016)
			(stroke
				(width 0.1)
				(type default)
			)
			(layer "B.Fab")
		)
		(pad "1" smd rect
			(at 0 0)
			(size 0.508 0.508)
			(layers "B.Cu" "B.Mask" "B.Paste")
			(net "VSENSE_PVCCIN_CPU1_N")
		)
		(pad "2" smd rect
			(at 0 0.889)
			(size 0.508 0.508)
			(layers "B.Cu" "B.Mask" "B.Paste")
			(net "GND")
		)
		(zone
			(layer "B.Cu")
			(hatch none 0.5)
			(connect_pads
				(clearance 0)
			)
			(min_thickness 0.25)
			(keepout
				(tracks not_allowed)
				(vias allowed)
				(pads allowed)
				(copperpour not_allowed)
				(footprints allowed)
			)
			(placement
				(enabled no)
				(sheetname "")
			)
			(fill
				(thermal_gap 0.5)
				(thermal_bridge_width 0.5)
				(island_removal_mode 0)
			)
			(polygon
				(pts
					(xy 64.008 -65.4304) (xy 64.516 -65.4304) (xy 64.516 -65.0494) (xy 64.008 -65.0494)
				)
			)
		)
		(zone
			(layer "B.Cu")
			(hatch none 0.5)
			(connect_pads
				(clearance 0)
			)
			(min_thickness 0.25)
			(keepout
				(tracks allowed)
				(vias not_allowed)
				(pads allowed)
				(copperpour not_allowed)
				(footprints allowed)
			)
			(placement
				(enabled no)
				(sheetname "")
			)
			(fill
				(thermal_gap 0.5)
				(thermal_bridge_width 0.5)
				(island_removal_mode 0)
			)
			(polygon
				(pts
					(xy 64.008 -65.0494) (xy 64.516 -65.0494) (xy 64.516 -65.4304) (xy 64.008 -65.4304)
				)
			)
		)
	)
	(footprint ""
		(layer "B.Cu")
		(at 96.45904 -157.02788 -90)
		(property "Reference" "C8L4"
			(at -1.47828 0.78994 0)
			(unlocked yes)
			(layer "B.SilkS")
			(effects
				(font
					(size 0.4064 0.254)
					(thickness 0.1524)
				)
				(justify mirror)
			)
		)
		(property "Value" ""
			(at 0 0 90)
			(layer "B.Fab")
			(effects
				(font
					(size 1.27 1.27)
				)
				(justify mirror)
			)
		)
		(duplicate_pad_numbers_are_jumpers no)
		(fp_poly
			(pts
				(xy 0.7239 -0.2159) (xy -0.7239 -0.2159) (xy -0.7239 1.9939) (xy 0.7239 1.9939)
			)
			(stroke
				(width 0)
				(type default)
			)
			(fill no)
			(layer "B.CrtYd")
		)
		(fp_line
			(start -0.7239 1.9939)
			(end -0.7239 -0.2159)
			(stroke
				(width 0.1)
				(type default)
			)
			(layer "B.Fab")
		)
		(fp_line
			(start 0.7239 1.9939)
			(end -0.7239 1.9939)
			(stroke
				(width 0.1)
				(type default)
			)
			(layer "B.Fab")
		)
		(fp_line
			(start -0.7239 -0.2159)
			(end 0.7239 -0.2159)
			(stroke
				(width 0.1)
				(type default)
			)
			(layer "B.Fab")
		)
		(fp_line
			(start 0.7239 -0.2159)
			(end 0.7239 1.9939)
			(stroke
				(width 0.1)
				(type default)
			)
			(layer "B.Fab")
		)
		(pad "1" smd rect
			(at 0 0 90)
			(size 1.27 1.016)
			(layers "B.Cu" "B.Mask" "B.Paste")
			(net "PVTT_KLM")
		)
		(pad "2" smd rect
			(at 0 1.778 90)
			(size 1.27 1.016)
			(layers "B.Cu" "B.Mask" "B.Paste")
			(net "GND")
		)
		(zone
			(layer "B.Cu")
			(hatch none 0.5)
			(connect_pads
				(clearance 0)
			)
			(min_thickness 0.25)
			(keepout
				(tracks not_allowed)
				(vias allowed)
				(pads allowed)
				(copperpour not_allowed)
				(footprints allowed)
			)
			(placement
				(enabled no)
				(sheetname "")
			)
			(fill
				(thermal_gap 0.5)
				(thermal_bridge_width 0.5)
				(island_removal_mode 0)
			)
			(polygon
				(pts
					(xy 95.95104 -156.39288) (xy 95.95104 -157.66288) (xy 95.18904 -157.66288) (xy 95.18904 -156.39288)
				)
			)
		)
	)
	(footprint ""
		(layer "B.Cu")
		(at 117.094 -81.483962)
		(property "Reference" "R7P5"
			(at 0 0 0)
			(layer "B.SilkS")
			(hide yes)
			(effects
				(font
					(size 1.27 1.27)
				)
				(justify mirror)
			)
		)
		(property "Value" ""
			(at 0 0 0)
			(layer "B.Fab")
			(effects
				(font
					(size 1.27 1.27)
				)
				(justify mirror)
			)
		)
		(duplicate_pad_numbers_are_jumpers no)
		(fp_poly
			(pts
				(xy 0.2794 -0.1016) (xy -0.2794 -0.1016) (xy -0.2794 0.9906) (xy 0.2794 0.9906)
			)
			(stroke
				(width 0)
				(type default)
			)
			(fill no)
			(layer "B.CrtYd")
		)
		(fp_line
			(start -0.2794 -0.1016)
			(end 0.2794 -0.1016)
			(stroke
				(width 0.1)
				(type default)
			)
			(layer "B.Fab")
		)
		(fp_line
			(start -0.2794 0.9906)
			(end -0.2794 -0.1016)
			(stroke
				(width 0.1)
				(type default)
			)
			(layer "B.Fab")
		)
		(fp_line
			(start 0.2794 -0.1016)
			(end 0.2794 0.9906)
			(stroke
				(width 0.1)
				(type default)
			)
			(layer "B.Fab")
		)
		(fp_line
			(start 0.2794 0.9906)
			(end -0.2794 0.9906)
			(stroke
				(width 0.1)
				(type default)
			)
			(layer "B.Fab")
		)
		(pad "1" smd rect
			(at 0 0 180)
			(size 0.508 0.508)
			(layers "B.Cu" "B.Mask" "B.Paste")
			(net "H_CPU1_MEMGHJ_MEMHOT_G_N")
		)
		(pad "2" smd rect
			(at 0 0.889 180)
			(size 0.508 0.508)
			(layers "B.Cu" "B.Mask" "B.Paste")
			(net "PVCCIO_CPU1")
		)
		(zone
			(layer "B.Cu")
			(hatch none 0.5)
			(connect_pads
				(clearance 0)
			)
			(min_thickness 0.25)
			(keepout
				(tracks allowed)
				(vias not_allowed)
				(pads allowed)
				(copperpour not_allowed)
				(footprints allowed)
			)
			(placement
				(enabled no)
				(sheetname "")
			)
			(fill
				(thermal_gap 0.5)
				(thermal_bridge_width 0.5)
				(island_removal_mode 0)
			)
			(polygon
				(pts
					(xy 117.348 -81.229962) (xy 116.84 -81.229962) (xy 116.84 -80.848962) (xy 117.348 -80.848962)
				)
			)
		)
		(zone
			(layer "B.Cu")
			(hatch none 0.5)
			(connect_pads
				(clearance 0)
			)
			(min_thickness 0.25)
			(keepout
				(tracks not_allowed)
				(vias allowed)
				(pads allowed)
				(copperpour not_allowed)
				(footprints allowed)
			)
			(placement
				(enabled no)
				(sheetname "")
			)
			(fill
				(thermal_gap 0.5)
				(thermal_bridge_width 0.5)
				(island_removal_mode 0)
			)
			(polygon
				(pts
					(xy 117.348 -80.848962) (xy 116.84 -80.848962) (xy 116.84 -81.229962) (xy 117.348 -81.229962)
				)
			)
		)
	)
	(footprint ""
		(layer "B.Cu")
		(at 418.61486 -30.13456 90)
		(property "Reference" "C25W43"
			(at 0.8382 -0.67818 90)
			(unlocked yes)
			(layer "B.SilkS")
			(effects
				(font
					(size 0.4064 0.254)
					(thickness 0.1524)
				)
				(justify left mirror)
			)
		)
		(property "Value" ""
			(at 0 0 90)
			(layer "B.Fab")
			(effects
				(font
					(size 1.27 1.27)
				)
				(justify mirror)
			)
		)
		(duplicate_pad_numbers_are_jumpers no)
		(fp_poly
			(pts
				(xy -0.3048 -0.1016) (xy -0.3048 0.9906) (xy 0.3048 0.9906) (xy 0.3048 -0.1016)
			)
			(stroke
				(width 0)
				(type default)
			)
			(fill no)
			(layer "B.CrtYd")
		)
		(fp_line
			(start 0.3048 -0.1016)
			(end 0.3048 0.9906)
			(stroke
				(width 0.1)
				(type default)
			)
			(layer "B.Fab")
		)
		(fp_line
			(start -0.3048 -0.1016)
			(end 0.3048 -0.1016)
			(stroke
				(width 0.1)
				(type default)
			)
			(layer "B.Fab")
		)
		(fp_line
			(start 0.3048 0.9906)
			(end -0.3048 0.9906)
			(stroke
				(width 0.1)
				(type default)
			)
			(layer "B.Fab")
		)
		(fp_line
			(start -0.3048 0.9906)
			(end -0.3048 -0.1016)
			(stroke
				(width 0.1)
				(type default)
			)
			(layer "B.Fab")
		)
		(pad "1" smd rect
			(at 0 0 270)
			(size 0.508 0.508)
			(layers "B.Cu" "B.Mask" "B.Paste")
			(net "VCC_D_3V3")
		)
		(pad "2" smd rect
			(at 0 0.889 270)
			(size 0.508 0.508)
			(layers "B.Cu" "B.Mask" "B.Paste")
			(net "GND")
		)
		(zone
			(layer "B.Cu")
			(hatch none 0.5)
			(connect_pads
				(clearance 0)
			)
			(min_thickness 0.25)
			(keepout
				(tracks allowed)
				(vias not_allowed)
				(pads allowed)
				(copperpour not_allowed)
				(footprints allowed)
			)
			(placement
				(enabled no)
				(sheetname "")
			)
			(fill
				(thermal_gap 0.5)
				(thermal_bridge_width 0.5)
				(island_removal_mode 0)
			)
			(polygon
				(pts
					(xy 418.86886 -30.38856) (xy 418.86886 -29.88056) (xy 419.24986 -29.88056) (xy 419.24986 -30.38856)
				)
			)
		)
		(zone
			(layer "B.Cu")
			(hatch none 0.5)
			(connect_pads
				(clearance 0)
			)
			(min_thickness 0.25)
			(keepout
				(tracks not_allowed)
				(vias allowed)
				(pads allowed)
				(copperpour not_allowed)
				(footprints allowed)
			)
			(placement
				(enabled no)
				(sheetname "")
			)
			(fill
				(thermal_gap 0.5)
				(thermal_bridge_width 0.5)
				(island_removal_mode 0)
			)
			(polygon
				(pts
					(xy 419.24986 -30.38856) (xy 419.24986 -29.88056) (xy 418.86886 -29.88056) (xy 418.86886 -30.38856)
				)
			)
		)
	)
)
